(kicad_pcb
	(version 20260206)
	(generator "pcbnew")
	(generator_version "10.0")
	(general
		(thickness 1.6)
		(legacy_teardrops no)
	)
	(paper "A4")
	(title_block
		(title "12092022_DA0F0TMDCD0_F0T_Management_Board_D_brd_V3_OCP.brd")
		(comment 1 "Grand Teton / footprints 798-803 of 1440")
	)
	(layers
		(0 "F.Cu" signal "TOP")
		(4 "In1.Cu" signal "GND")
		(6 "In2.Cu" signal "IN1")
		(8 "In3.Cu" signal "GND1")
		(10 "In4.Cu" signal "IN2")
		(12 "In5.Cu" signal "VCC")
		(14 "In6.Cu" signal "VCC1")
		(16 "In7.Cu" signal "IN3")
		(18 "In8.Cu" signal "GND2")
		(20 "In9.Cu" signal "IN4")
		(22 "In10.Cu" signal "GND3")
		(2 "B.Cu" signal "BOTTOM")
		(9 "F.Adhes" user "F.Adhesive")
		(11 "B.Adhes" user "B.Adhesive")
		(13 "F.Paste" user "Package Geometry/Pastemask Top")
		(15 "B.Paste" user "Package Geometry/Pastemask Bottom")
		(5 "F.SilkS" user "Ref Des/Silkscreen Top")
		(7 "B.SilkS" user "Ref Des/Silkscreen Bottom")
		(1 "F.Mask" user "Board Geometry/Soldermask Top")
		(3 "B.Mask" user "Board Geometry/Soldermask Bottom")
		(17 "Dwgs.User" user "User.Drawings")
		(19 "Cmts.User" user "User.Comments")
		(21 "Eco1.User" user "User.Eco1")
		(23 "Eco2.User" user "User.Eco2")
		(25 "Edge.Cuts" user "Board Geometry/Outline")
		(27 "Margin" user)
		(31 "F.CrtYd" user "Package Geometry/Place Bound Top")
		(29 "B.CrtYd" user "Package Geometry/Place Bound Bottom")
		(35 "F.Fab" user "Ref Des/Assembly Top")
		(33 "B.Fab" user "Ref Des/Assembly Bottom")
	)
	(footprint ""
		(layer "B.Cu")
		(at 17.526 -98.679 90)
		(property "Reference" "R525"
			(at 0 0 90)
			(layer "B.SilkS")
			(hide yes)
			(effects
				(font
					(size 1.27 1.27)
				)
				(justify mirror)
			)
		)
		(property "Value" ""
			(at 0 0 90)
			(layer "B.Fab")
			(effects
				(font
					(size 1.27 1.27)
				)
				(justify mirror)
			)
		)
		(duplicate_pad_numbers_are_jumpers no)
		(fp_line
			(start 0.7874 -0.4064)
			(end -0.7874 -0.4064)
			(stroke
				(width 0.1524)
				(type default)
			)
			(layer "B.SilkS")
		)
		(fp_line
			(start -0.7874 -0.4064)
			(end -0.7874 0.4064)
			(stroke
				(width 0.1524)
				(type default)
			)
			(layer "B.SilkS")
		)
		(fp_line
			(start 0.7874 0.4064)
			(end 0.7874 -0.4064)
			(stroke
				(width 0.1524)
				(type default)
			)
			(layer "B.SilkS")
		)
		(fp_line
			(start -0.7874 0.4064)
			(end 0.7874 0.4064)
			(stroke
				(width 0.1524)
				(type default)
			)
			(layer "B.SilkS")
		)
		(fp_line
			(start 0.67945 -0.305054)
			(end 0.12065 -0.305054)
			(stroke
				(width 0.1)
				(type default)
			)
			(layer "B.Fab")
		)
		(fp_line
			(start 0.12065 -0.305054)
			(end 0.12065 -0.2794)
			(stroke
				(width 0.1)
				(type default)
			)
			(layer "B.Fab")
		)
		(fp_line
			(start -0.12065 -0.3048)
			(end -0.67945 -0.3048)
			(stroke
				(width 0.1)
				(type default)
			)
			(layer "B.Fab")
		)
		(fp_line
			(start -0.67945 -0.3048)
			(end -0.67945 0.3048)
			(stroke
				(width 0.1)
				(type default)
			)
			(layer "B.Fab")
		)
		(fp_line
			(start 0.12065 -0.2794)
			(end -0.12065 -0.2794)
			(stroke
				(width 0.1)
				(type default)
			)
			(layer "B.Fab")
		)
		(fp_line
			(start -0.12065 -0.2794)
			(end -0.12065 -0.3048)
			(stroke
				(width 0.1)
				(type default)
			)
			(layer "B.Fab")
		)
		(fp_line
			(start 0.12065 0.2794)
			(end 0.12065 0.3048)
			(stroke
				(width 0.1)
				(type default)
			)
			(layer "B.Fab")
		)
		(fp_line
			(start -0.120396 0.2794)
			(end 0.12065 0.2794)
			(stroke
				(width 0.1)
				(type default)
			)
			(layer "B.Fab")
		)
		(fp_line
			(start 0.67945 0.3048)
			(end 0.67945 -0.305054)
			(stroke
				(width 0.1)
				(type default)
			)
			(layer "B.Fab")
		)
		(fp_line
			(start 0.12065 0.3048)
			(end 0.67945 0.3048)
			(stroke
				(width 0.1)
				(type default)
			)
			(layer "B.Fab")
		)
		(fp_line
			(start -0.120396 0.3048)
			(end -0.120396 0.2794)
			(stroke
				(width 0.1)
				(type default)
			)
			(layer "B.Fab")
		)
		(fp_line
			(start -0.67945 0.3048)
			(end -0.120396 0.3048)
			(stroke
				(width 0.1)
				(type default)
			)
			(layer "B.Fab")
		)
		(pad "1" smd circle
			(at 0.40005 0 270)
			(size 0 0)
			(layers "B.Cu" "B.Mask" "B.Paste")
			(net "P3V3_AUX")
		)
		(pad "2" smd circle
			(at -0.40005 0 270)
			(size 0 0)
			(layers "B.Cu" "B.Mask" "B.Paste")
			(net "VCCIO1")
		)
	)
	(footprint ""
		(layer "B.Cu")
		(at 82.108294 -51.730656 180)
		(property "Reference" "R324"
			(at 0 0 0)
			(layer "B.SilkS")
			(hide yes)
			(effects
				(font
					(size 1.27 1.27)
				)
				(justify mirror)
			)
		)
		(property "Value" ""
			(at 0 0 0)
			(layer "B.Fab")
			(effects
				(font
					(size 1.27 1.27)
				)
				(justify mirror)
			)
		)
		(duplicate_pad_numbers_are_jumpers no)
		(fp_line
			(start 0.7874 0.4064)
			(end 0.7874 -0.4064)
			(stroke
				(width 0.1524)
				(type default)
			)
			(layer "B.SilkS")
		)
		(fp_line
			(start 0.7874 -0.4064)
			(end -0.7874 -0.4064)
			(stroke
				(width 0.1524)
				(type default)
			)
			(layer "B.SilkS")
		)
		(fp_line
			(start -0.7874 0.4064)
			(end 0.7874 0.4064)
			(stroke
				(width 0.1524)
				(type default)
			)
			(layer "B.SilkS")
		)
		(fp_line
			(start -0.7874 -0.4064)
			(end -0.7874 0.4064)
			(stroke
				(width 0.1524)
				(type default)
			)
			(layer "B.SilkS")
		)
		(fp_line
			(start 0.67945 0.3048)
			(end 0.67945 -0.305054)
			(stroke
				(width 0.1)
				(type default)
			)
			(layer "B.Fab")
		)
		(fp_line
			(start 0.67945 -0.305054)
			(end 0.12065 -0.305054)
			(stroke
				(width 0.1)
				(type default)
			)
			(layer "B.Fab")
		)
		(fp_line
			(start 0.12065 0.3048)
			(end 0.67945 0.3048)
			(stroke
				(width 0.1)
				(type default)
			)
			(layer "B.Fab")
		)
		(fp_line
			(start 0.12065 0.2794)
			(end 0.12065 0.3048)
			(stroke
				(width 0.1)
				(type default)
			)
			(layer "B.Fab")
		)
		(fp_line
			(start 0.12065 -0.2794)
			(end -0.12065 -0.2794)
			(stroke
				(width 0.1)
				(type default)
			)
			(layer "B.Fab")
		)
		(fp_line
			(start 0.12065 -0.305054)
			(end 0.12065 -0.2794)
			(stroke
				(width 0.1)
				(type default)
			)
			(layer "B.Fab")
		)
		(fp_line
			(start -0.120396 0.3048)
			(end -0.120396 0.2794)
			(stroke
				(width 0.1)
				(type default)
			)
			(layer "B.Fab")
		)
		(fp_line
			(start -0.120396 0.2794)
			(end 0.12065 0.2794)
			(stroke
				(width 0.1)
				(type default)
			)
			(layer "B.Fab")
		)
		(fp_line
			(start -0.12065 -0.2794)
			(end -0.12065 -0.3048)
			(stroke
				(width 0.1)
				(type default)
			)
			(layer "B.Fab")
		)
		(fp_line
			(start -0.12065 -0.3048)
			(end -0.67945 -0.3048)
			(stroke
				(width 0.1)
				(type default)
			)
			(layer "B.Fab")
		)
		(fp_line
			(start -0.67945 0.3048)
			(end -0.120396 0.3048)
			(stroke
				(width 0.1)
				(type default)
			)
			(layer "B.Fab")
		)
		(fp_line
			(start -0.67945 -0.3048)
			(end -0.67945 0.3048)
			(stroke
				(width 0.1)
				(type default)
			)
			(layer "B.Fab")
		)
		(pad "1" smd circle
			(at 0.40005 0)
			(size 0 0)
			(layers "B.Cu" "B.Mask" "B.Paste")
			(net "P1V2_AUX")
		)
		(pad "2" smd circle
			(at -0.40005 0)
			(size 0 0)
			(layers "B.Cu" "B.Mask" "B.Paste")
			(net "P0V6_DDR_VREF_AUX")
		)
	)
	(footprint ""
		(layer "B.Cu")
		(at 19.431 -17.907 90)
		(property "Reference" "R53"
			(at 0 0 90)
			(layer "B.SilkS")
			(hide yes)
			(effects
				(font
					(size 1.27 1.27)
				)
				(justify mirror)
			)
		)
		(property "Value" ""
			(at 0 0 90)
			(layer "B.Fab")
			(effects
				(font
					(size 1.27 1.27)
				)
				(justify mirror)
			)
		)
		(duplicate_pad_numbers_are_jumpers no)
		(fp_line
			(start 0.7874 -0.4064)
			(end -0.7874 -0.4064)
			(stroke
				(width 0.1524)
				(type default)
			)
			(layer "B.SilkS")
		)
		(fp_line
			(start -0.7874 -0.4064)
			(end -0.7874 0.4064)
			(stroke
				(width 0.1524)
				(type default)
			)
			(layer "B.SilkS")
		)
		(fp_line
			(start 0.7874 0.4064)
			(end 0.7874 -0.4064)
			(stroke
				(width 0.1524)
				(type default)
			)
			(layer "B.SilkS")
		)
		(fp_line
			(start -0.7874 0.4064)
			(end 0.7874 0.4064)
			(stroke
				(width 0.1524)
				(type default)
			)
			(layer "B.SilkS")
		)
		(fp_line
			(start 0.67945 -0.305054)
			(end 0.12065 -0.305054)
			(stroke
				(width 0.1)
				(type default)
			)
			(layer "B.Fab")
		)
		(fp_line
			(start 0.12065 -0.305054)
			(end 0.12065 -0.2794)
			(stroke
				(width 0.1)
				(type default)
			)
			(layer "B.Fab")
		)
		(fp_line
			(start -0.12065 -0.3048)
			(end -0.67945 -0.3048)
			(stroke
				(width 0.1)
				(type default)
			)
			(layer "B.Fab")
		)
		(fp_line
			(start -0.67945 -0.3048)
			(end -0.67945 0.3048)
			(stroke
				(width 0.1)
				(type default)
			)
			(layer "B.Fab")
		)
		(fp_line
			(start 0.12065 -0.2794)
			(end -0.12065 -0.2794)
			(stroke
				(width 0.1)
				(type default)
			)
			(layer "B.Fab")
		)
		(fp_line
			(start -0.12065 -0.2794)
			(end -0.12065 -0.3048)
			(stroke
				(width 0.1)
				(type default)
			)
			(layer "B.Fab")
		)
		(fp_line
			(start 0.12065 0.2794)
			(end 0.12065 0.3048)
			(stroke
				(width 0.1)
				(type default)
			)
			(layer "B.Fab")
		)
		(fp_line
			(start -0.120396 0.2794)
			(end 0.12065 0.2794)
			(stroke
				(width 0.1)
				(type default)
			)
			(layer "B.Fab")
		)
		(fp_line
			(start 0.67945 0.3048)
			(end 0.67945 -0.305054)
			(stroke
				(width 0.1)
				(type default)
			)
			(layer "B.Fab")
		)
		(fp_line
			(start 0.12065 0.3048)
			(end 0.67945 0.3048)
			(stroke
				(width 0.1)
				(type default)
			)
			(layer "B.Fab")
		)
		(fp_line
			(start -0.120396 0.3048)
			(end -0.120396 0.2794)
			(stroke
				(width 0.1)
				(type default)
			)
			(layer "B.Fab")
		)
		(fp_line
			(start -0.67945 0.3048)
			(end -0.120396 0.3048)
			(stroke
				(width 0.1)
				(type default)
			)
			(layer "B.Fab")
		)
		(pad "1" smd circle
			(at 0.40005 0 270)
			(size 0 0)
			(layers "B.Cu" "B.Mask" "B.Paste")
			(net "TMC75_A1")
		)
		(pad "2" smd circle
			(at -0.40005 0 270)
			(size 0 0)
			(layers "B.Cu" "B.Mask" "B.Paste")
			(net "GND")
		)
	)
	(footprint ""
		(layer "B.Cu")
		(at 62.865 -31.369 -90)
		(property "Reference" "R491"
			(at 0 0 90)
			(layer "B.SilkS")
			(hide yes)
			(effects
				(font
					(size 1.27 1.27)
				)
				(justify mirror)
			)
		)
		(property "Value" ""
			(at 0 0 90)
			(layer "B.Fab")
			(effects
				(font
					(size 1.27 1.27)
				)
				(justify mirror)
			)
		)
		(duplicate_pad_numbers_are_jumpers no)
		(fp_line
			(start -0.7874 0.4064)
			(end 0.7874 0.4064)
			(stroke
				(width 0.1524)
				(type default)
			)
			(layer "B.SilkS")
		)
		(fp_line
			(start 0.7874 0.4064)
			(end 0.7874 -0.4064)
			(stroke
				(width 0.1524)
				(type default)
			)
			(layer "B.SilkS")
		)
		(fp_line
			(start -0.7874 -0.4064)
			(end -0.7874 0.4064)
			(stroke
				(width 0.1524)
				(type default)
			)
			(layer "B.SilkS")
		)
		(fp_line
			(start 0.7874 -0.4064)
			(end -0.7874 -0.4064)
			(stroke
				(width 0.1524)
				(type default)
			)
			(layer "B.SilkS")
		)
		(fp_line
			(start -0.67945 0.3048)
			(end -0.120396 0.3048)
			(stroke
				(width 0.1)
				(type default)
			)
			(layer "B.Fab")
		)
		(fp_line
			(start -0.120396 0.3048)
			(end -0.120396 0.2794)
			(stroke
				(width 0.1)
				(type default)
			)
			(layer "B.Fab")
		)
		(fp_line
			(start 0.12065 0.3048)
			(end 0.67945 0.3048)
			(stroke
				(width 0.1)
				(type default)
			)
			(layer "B.Fab")
		)
		(fp_line
			(start 0.67945 0.3048)
			(end 0.67945 -0.305054)
			(stroke
				(width 0.1)
				(type default)
			)
			(layer "B.Fab")
		)
		(fp_line
			(start -0.120396 0.2794)
			(end 0.12065 0.2794)
			(stroke
				(width 0.1)
				(type default)
			)
			(layer "B.Fab")
		)
		(fp_line
			(start 0.12065 0.2794)
			(end 0.12065 0.3048)
			(stroke
				(width 0.1)
				(type default)
			)
			(layer "B.Fab")
		)
		(fp_line
			(start -0.12065 -0.2794)
			(end -0.12065 -0.3048)
			(stroke
				(width 0.1)
				(type default)
			)
			(layer "B.Fab")
		)
		(fp_line
			(start 0.12065 -0.2794)
			(end -0.12065 -0.2794)
			(stroke
				(width 0.1)
				(type default)
			)
			(layer "B.Fab")
		)
		(fp_line
			(start -0.67945 -0.3048)
			(end -0.67945 0.3048)
			(stroke
				(width 0.1)
				(type default)
			)
			(layer "B.Fab")
		)
		(fp_line
			(start -0.12065 -0.3048)
			(end -0.67945 -0.3048)
			(stroke
				(width 0.1)
				(type default)
			)
			(layer "B.Fab")
		)
		(fp_line
			(start 0.12065 -0.305054)
			(end 0.12065 -0.2794)
			(stroke
				(width 0.1)
				(type default)
			)
			(layer "B.Fab")
		)
		(fp_line
			(start 0.67945 -0.305054)
			(end 0.12065 -0.305054)
			(stroke
				(width 0.1)
				(type default)
			)
			(layer "B.Fab")
		)
		(pad "1" smd circle
			(at 0.40005 0 90)
			(size 0 0)
			(layers "B.Cu" "B.Mask" "B.Paste")
			(net "P3V3_RGM")
		)
		(pad "2" smd circle
			(at -0.40005 0 90)
			(size 0 0)
			(layers "B.Cu" "B.Mask" "B.Paste")
			(net "RST_BMC_SRST_N")
		)
	)
	(footprint ""
		(layer "B.Cu")
		(at 73.516998 -47.730156)
		(property "Reference" "C16"
			(at 0 0 0)
			(layer "B.SilkS")
			(hide yes)
			(effects
				(font
					(size 1.27 1.27)
				)
				(justify mirror)
			)
		)
		(property "Value" ""
			(at 0 0 0)
			(layer "B.Fab")
			(effects
				(font
					(size 1.27 1.27)
				)
				(justify mirror)
			)
		)
		(duplicate_pad_numbers_are_jumpers no)
		(fp_line
			(start -0.7874 -0.4064)
			(end -0.7874 0.4064)
			(stroke
				(width 0.1524)
				(type default)
			)
			(layer "B.SilkS")
		)
		(fp_line
			(start -0.7874 0.4064)
			(end 0.7874 0.4064)
			(stroke
				(width 0.1524)
				(type default)
			)
			(layer "B.SilkS")
		)
		(fp_line
			(start 0.7874 -0.4064)
			(end -0.7874 -0.4064)
			(stroke
				(width 0.1524)
				(type default)
			)
			(layer "B.SilkS")
		)
		(fp_line
			(start 0.7874 0.4064)
			(end 0.7874 -0.4064)
			(stroke
				(width 0.1524)
				(type default)
			)
			(layer "B.SilkS")
		)
		(fp_line
			(start -0.67945 -0.3048)
			(end -0.67945 0.3048)
			(stroke
				(width 0.1)
				(type default)
			)
			(layer "B.Fab")
		)
		(fp_line
			(start -0.67945 0.3048)
			(end -0.120396 0.3048)
			(stroke
				(width 0.1)
				(type default)
			)
			(layer "B.Fab")
		)
		(fp_line
			(start -0.12065 -0.3048)
			(end -0.67945 -0.3048)
			(stroke
				(width 0.1)
				(type default)
			)
			(layer "B.Fab")
		)
		(fp_line
			(start -0.12065 -0.2794)
			(end -0.12065 -0.3048)
			(stroke
				(width 0.1)
				(type default)
			)
			(layer "B.Fab")
		)
		(fp_line
			(start -0.120396 0.2794)
			(end 0.12065 0.2794)
			(stroke
				(width 0.1)
				(type default)
			)
			(layer "B.Fab")
		)
		(fp_line
			(start -0.120396 0.3048)
			(end -0.120396 0.2794)
			(stroke
				(width 0.1)
				(type default)
			)
			(layer "B.Fab")
		)
		(fp_line
			(start 0.12065 -0.305054)
			(end 0.12065 -0.2794)
			(stroke
				(width 0.1)
				(type default)
			)
			(layer "B.Fab")
		)
		(fp_line
			(start 0.12065 -0.2794)
			(end -0.12065 -0.2794)
			(stroke
				(width 0.1)
				(type default)
			)
			(layer "B.Fab")
		)
		(fp_line
			(start 0.12065 0.2794)
			(end 0.12065 0.3048)
			(stroke
				(width 0.1)
				(type default)
			)
			(layer "B.Fab")
		)
		(fp_line
			(start 0.12065 0.3048)
			(end 0.67945 0.3048)
			(stroke
				(width 0.1)
				(type default)
			)
			(layer "B.Fab")
		)
		(fp_line
			(start 0.67945 -0.305054)
			(end 0.12065 -0.305054)
			(stroke
				(width 0.1)
				(type default)
			)
			(layer "B.Fab")
		)
		(fp_line
			(start 0.67945 0.3048)
			(end 0.67945 -0.305054)
			(stroke
				(width 0.1)
				(type default)
			)
			(layer "B.Fab")
		)
		(pad "1" smd circle
			(at 0.40005 0 180)
			(size 0 0)
			(layers "B.Cu" "B.Mask" "B.Paste")
			(net "P1V2_AUX")
		)
		(pad "2" smd circle
			(at -0.40005 0 180)
			(size 0 0)
			(layers "B.Cu" "B.Mask" "B.Paste")
			(net "GND")
		)
	)
	(footprint ""
		(layer "B.Cu")
		(at 84.452968 -98.20529 180)
		(property "Reference" "C249"
			(at 0 0 0)
			(layer "B.SilkS")
			(hide yes)
			(effects
				(font
					(size 1.27 1.27)
				)
				(justify mirror)
			)
		)
		(property "Value" ""
			(at 0 0 0)
			(layer "B.Fab")
			(effects
				(font
					(size 1.27 1.27)
				)
				(justify mirror)
			)
		)
		(duplicate_pad_numbers_are_jumpers no)
		(fp_line
			(start 0.7874 0.4064)
			(end 0.7874 -0.4064)
			(stroke
				(width 0.1524)
				(type default)
			)
			(layer "B.SilkS")
		)
		(fp_line
			(start 0.7874 -0.4064)
			(end -0.7874 -0.4064)
			(stroke
				(width 0.1524)
				(type default)
			)
			(layer "B.SilkS")
		)
		(fp_line
			(start -0.7874 0.4064)
			(end 0.7874 0.4064)
			(stroke
				(width 0.1524)
				(type default)
			)
			(layer "B.SilkS")
		)
		(fp_line
			(start -0.7874 -0.4064)
			(end -0.7874 0.4064)
			(stroke
				(width 0.1524)
				(type default)
			)
			(layer "B.SilkS")
		)
		(fp_line
			(start 0.67945 0.3048)
			(end 0.67945 -0.305054)
			(stroke
				(width 0.1)
				(type default)
			)
			(layer "B.Fab")
		)
		(fp_line
			(start 0.67945 -0.305054)
			(end 0.12065 -0.305054)
			(stroke
				(width 0.1)
				(type default)
			)
			(layer "B.Fab")
		)
		(fp_line
			(start 0.12065 0.3048)
			(end 0.67945 0.3048)
			(stroke
				(width 0.1)
				(type default)
			)
			(layer "B.Fab")
		)
		(fp_line
			(start 0.12065 0.2794)
			(end 0.12065 0.3048)
			(stroke
				(width 0.1)
				(type default)
			)
			(layer "B.Fab")
		)
		(fp_line
			(start 0.12065 -0.2794)
			(end -0.12065 -0.2794)
			(stroke
				(width 0.1)
				(type default)
			)
			(layer "B.Fab")
		)
		(fp_line
			(start 0.12065 -0.305054)
			(end 0.12065 -0.2794)
			(stroke
				(width 0.1)
				(type default)
			)
			(layer "B.Fab")
		)
		(fp_line
			(start -0.120396 0.3048)
			(end -0.120396 0.2794)
			(stroke
				(width 0.1)
				(type default)
			)
			(layer "B.Fab")
		)
		(fp_line
			(start -0.120396 0.2794)
			(end 0.12065 0.2794)
			(stroke
				(width 0.1)
				(type default)
			)
			(layer "B.Fab")
		)
		(fp_line
			(start -0.12065 -0.2794)
			(end -0.12065 -0.3048)
			(stroke
				(width 0.1)
				(type default)
			)
			(layer "B.Fab")
		)
		(fp_line
			(start -0.12065 -0.3048)
			(end -0.67945 -0.3048)
			(stroke
				(width 0.1)
				(type default)
			)
			(layer "B.Fab")
		)
		(fp_line
			(start -0.67945 0.3048)
			(end -0.120396 0.3048)
			(stroke
				(width 0.1)
				(type default)
			)
			(layer "B.Fab")
		)
		(fp_line
			(start -0.67945 -0.3048)
			(end -0.67945 0.3048)
			(stroke
				(width 0.1)
				(type default)
			)
			(layer "B.Fab")
		)
		(pad "1" smd circle
			(at 0.40005 0)
			(size 0 0)
			(layers "B.Cu" "B.Mask" "B.Paste")
			(net "P3V3_AUX")
		)
		(pad "2" smd circle
			(at -0.40005 0)
			(size 0 0)
			(layers "B.Cu" "B.Mask" "B.Paste")
			(net "GND")
		)
	)
)
